# S9S_MB_2U (Grand Teton) — schematic netlist excerpt (pin names and nets, part order shuffled) for the footprints in the layout excerpt that follows; sources: Cadence DE-HDL packaged netlist, KiCad conversion of 03242023_DA0F0TMBIJ0_F0T_Motherboard_J_brd_V01_OCP.brd

R20  Q_RES  0 5% CHIP  pkg 0402LF  page 16 : A = DBP_CPU_MBP0_GTL_N ; B = FM_PCH_TRIGGER0_N
C453  Q_CAP  47UF 4V 20% X6S  pkg C0805  page 78 : A = PVCCFA_EHV_FIVRA_CPU1 ; B = GND
R2358  Q_RES  0 5% CHIP  pkg 0402LF  page 263 : A = FM_PCH_P1V8_AUX_EN ; B = FM_PCH_P1V8_AUX_EN_R

(kicad_pcb
	(version 20260206)
	(generator "pcbnew")
	(generator_version "10.0")
	(general
		(thickness 1.6)
		(legacy_teardrops no)
	)
	(paper "A4")
	(title_block
		(title "03242023_DA0F0TMBIJ0_F0T_Motherboard_J_brd_V01_OCP.brd")
		(comment 1 "Grand Teton / footprints 4798-4800 of 6105")
	)
	(layers
		(0 "F.Cu" signal "TOP")
		(4 "In1.Cu" signal "GND")
		(6 "In2.Cu" signal "IN1")
		(8 "In3.Cu" signal "GND1")
		(10 "In4.Cu" signal "IN2")
		(12 "In5.Cu" signal "GND2")
		(14 "In6.Cu" signal "IN3")
		(16 "In7.Cu" signal "GND3")
		(18 "In8.Cu" signal "VCC")
		(20 "In9.Cu" signal "VCC1")
		(22 "In10.Cu" signal "GND4")
		(24 "In11.Cu" signal "IN4")
		(26 "In12.Cu" signal "GND5")
		(28 "In13.Cu" signal "IN5")
		(30 "In14.Cu" signal "GND6")
		(32 "In15.Cu" signal "IN6")
		(34 "In16.Cu" signal "GND7")
		(2 "B.Cu" signal "BOTTOM")
		(9 "F.Adhes" user "F.Adhesive")
		(11 "B.Adhes" user "B.Adhesive")
		(13 "F.Paste" user "Package Geometry/Pastemask Top")
		(15 "B.Paste" user "Package Geometry/Pastemask Bottom")
		(5 "F.SilkS" user "Ref Des/Silkscreen Top")
		(7 "B.SilkS" user "Ref Des/Silkscreen Bottom")
		(1 "F.Mask" user "Board Geometry/Soldermask Top")
		(3 "B.Mask" user "Board Geometry/Soldermask Bottom")
		(17 "Dwgs.User" user "User.Drawings")
		(19 "Cmts.User" user "User.Comments")
		(21 "Eco1.User" user "User.Eco1")
		(23 "Eco2.User" user "User.Eco2")
		(25 "Edge.Cuts" user "Board Geometry/Outline")
		(27 "Margin" user)
		(31 "F.CrtYd" user "Package Geometry/Place Bound Top")
		(29 "B.CrtYd" user "Package Geometry/Place Bound Bottom")
		(35 "F.Fab" user "Ref Des/Assembly Top")
		(33 "B.Fab" user "Ref Des/Assembly Bottom")
	)
	(footprint ""
		(layer "B.Cu")
		(at 333.935578 -185.76925 180)
		(property "Reference" "R20"
			(at 0 0 0)
			(layer "B.SilkS")
			(hide yes)
			(effects
				(font
					(size 1.27 1.27)
				)
				(justify mirror)
			)
		)
		(property "Value" ""
			(at 0 0 0)
			(layer "B.Fab")
			(effects
				(font
					(size 1.27 1.27)
				)
				(justify mirror)
			)
		)
		(duplicate_pad_numbers_are_jumpers no)
		(fp_line
			(start 0.7874 0.4064)
			(end 0.7874 -0.4064)
			(stroke
				(width 0.1524)
				(type default)
			)
			(layer "B.SilkS")
		)
		(fp_line
			(start 0.7874 -0.4064)
			(end -0.7874 -0.4064)
			(stroke
				(width 0.1524)
				(type default)
			)
			(layer "B.SilkS")
		)
		(fp_line
			(start -0.7874 0.4064)
			(end 0.7874 0.4064)
			(stroke
				(width 0.1524)
				(type default)
			)
			(layer "B.SilkS")
		)
		(fp_line
			(start -0.7874 -0.4064)
			(end -0.7874 0.4064)
			(stroke
				(width 0.1524)
				(type default)
			)
			(layer "B.SilkS")
		)
		(fp_line
			(start 0.67945 0.3048)
			(end 0.67945 -0.305054)
			(stroke
				(width 0.1)
				(type default)
			)
			(layer "B.Fab")
		)
		(fp_line
			(start 0.67945 -0.305054)
			(end 0.12065 -0.305054)
			(stroke
				(width 0.1)
				(type default)
			)
			(layer "B.Fab")
		)
		(fp_line
			(start 0.12065 0.3048)
			(end 0.67945 0.3048)
			(stroke
				(width 0.1)
				(type default)
			)
			(layer "B.Fab")
		)
		(fp_line
			(start 0.12065 0.2794)
			(end 0.12065 0.3048)
			(stroke
				(width 0.1)
				(type default)
			)
			(layer "B.Fab")
		)
		(fp_line
			(start 0.12065 -0.2794)
			(end -0.12065 -0.2794)
			(stroke
				(width 0.1)
				(type default)
			)
			(layer "B.Fab")
		)
		(fp_line
			(start 0.12065 -0.305054)
			(end 0.12065 -0.2794)
			(stroke
				(width 0.1)
				(type default)
			)
			(layer "B.Fab")
		)
		(fp_line
			(start -0.120396 0.3048)
			(end -0.120396 0.2794)
			(stroke
				(width 0.1)
				(type default)
			)
			(layer "B.Fab")
		)
		(fp_line
			(start -0.120396 0.2794)
			(end 0.12065 0.2794)
			(stroke
				(width 0.1)
				(type default)
			)
			(layer "B.Fab")
		)
		(fp_line
			(start -0.12065 -0.2794)
			(end -0.12065 -0.3048)
			(stroke
				(width 0.1)
				(type default)
			)
			(layer "B.Fab")
		)
		(fp_line
			(start -0.12065 -0.3048)
			(end -0.67945 -0.3048)
			(stroke
				(width 0.1)
				(type default)
			)
			(layer "B.Fab")
		)
		(fp_line
			(start -0.67945 0.3048)
			(end -0.120396 0.3048)
			(stroke
				(width 0.1)
				(type default)
			)
			(layer "B.Fab")
		)
		(fp_line
			(start -0.67945 -0.3048)
			(end -0.67945 0.3048)
			(stroke
				(width 0.1)
				(type default)
			)
			(layer "B.Fab")
		)
		(pad "1" smd circle
			(at 0.40005 0)
			(size 0 0)
			(layers "B.Cu" "B.Mask" "B.Paste")
			(net "DBP_CPU_MBP0_GTL_N")
		)
		(pad "2" smd circle
			(at -0.40005 0)
			(size 0 0)
			(layers "B.Cu" "B.Mask" "B.Paste")
			(net "FM_PCH_TRIGGER0_N")
		)
	)
	(footprint ""
		(layer "B.Cu")
		(at 65.067688 -250.792996 90)
		(property "Reference" "C453"
			(at 0 0 90)
			(layer "B.SilkS")
			(hide yes)
			(effects
				(font
					(size 1.27 1.27)
				)
				(justify mirror)
			)
		)
		(property "Value" ""
			(at 0 0 90)
			(layer "B.Fab")
			(effects
				(font
					(size 1.27 1.27)
				)
				(justify mirror)
			)
		)
		(duplicate_pad_numbers_are_jumpers no)
		(fp_line
			(start 1.524 -0.762)
			(end -1.524 -0.762)
			(stroke
				(width 0.1524)
				(type default)
			)
			(layer "B.SilkS")
		)
		(fp_line
			(start -1.524 -0.762)
			(end -1.524 0.762)
			(stroke
				(width 0.1524)
				(type default)
			)
			(layer "B.SilkS")
		)
		(fp_line
			(start 1.524 0.762)
			(end 1.524 -0.762)
			(stroke
				(width 0.1524)
				(type default)
			)
			(layer "B.SilkS")
		)
		(fp_line
			(start -1.524 0.762)
			(end 1.524 0.762)
			(stroke
				(width 0.1524)
				(type default)
			)
			(layer "B.SilkS")
		)
		(fp_line
			(start 1.1049 -0.724916)
			(end 1.1049 0.724916)
			(stroke
				(width 0.1)
				(type default)
			)
			(layer "B.Fab")
		)
		(fp_line
			(start -1.1049 -0.724916)
			(end 1.1049 -0.724916)
			(stroke
				(width 0.1)
				(type default)
			)
			(layer "B.Fab")
		)
		(fp_line
			(start 1.1049 0.724916)
			(end -1.1049 0.724916)
			(stroke
				(width 0.1)
				(type default)
			)
			(layer "B.Fab")
		)
		(fp_line
			(start -1.1049 0.724916)
			(end -1.1049 -0.724916)
			(stroke
				(width 0.1)
				(type default)
			)
			(layer "B.Fab")
		)
		(pad "1" smd rect
			(at 0.889 0 90)
			(size 1.016 1.27)
			(layers "B.Cu" "B.Mask" "B.Paste")
			(net "PVCCFA_EHV_FIVRA_CPU1")
		)
		(pad "2" smd rect
			(at -0.889 0 90)
			(size 1.016 1.27)
			(layers "B.Cu" "B.Mask" "B.Paste")
			(net "GND")
		)
	)
	(footprint ""
		(layer "B.Cu")
		(at 383.650998 -80.09255 90)
		(property "Reference" "R2358"
			(at 0 0 90)
			(layer "B.SilkS")
			(hide yes)
			(effects
				(font
					(size 1.27 1.27)
				)
				(justify mirror)
			)
		)
		(property "Value" ""
			(at 0 0 90)
			(layer "B.Fab")
			(effects
				(font
					(size 1.27 1.27)
				)
				(justify mirror)
			)
		)
		(duplicate_pad_numbers_are_jumpers no)
		(fp_line
			(start 0.7874 -0.4064)
			(end -0.7874 -0.4064)
			(stroke
				(width 0.1524)
				(type default)
			)
			(layer "B.SilkS")
		)
		(fp_line
			(start -0.7874 -0.4064)
			(end -0.7874 0.4064)
			(stroke
				(width 0.1524)
				(type default)
			)
			(layer "B.SilkS")
		)
		(fp_line
			(start 0.7874 0.4064)
			(end 0.7874 -0.4064)
			(stroke
				(width 0.1524)
				(type default)
			)
			(layer "B.SilkS")
		)
		(fp_line
			(start -0.7874 0.4064)
			(end 0.7874 0.4064)
			(stroke
				(width 0.1524)
				(type default)
			)
			(layer "B.SilkS")
		)
		(fp_line
			(start 0.67945 -0.305054)
			(end 0.12065 -0.305054)
			(stroke
				(width 0.1)
				(type default)
			)
			(layer "B.Fab")
		)
		(fp_line
			(start 0.12065 -0.305054)
			(end 0.12065 -0.2794)
			(stroke
				(width 0.1)
				(type default)
			)
			(layer "B.Fab")
		)
		(fp_line
			(start -0.12065 -0.3048)
			(end -0.67945 -0.3048)
			(stroke
				(width 0.1)
				(type default)
			)
			(layer "B.Fab")
		)
		(fp_line
			(start -0.67945 -0.3048)
			(end -0.67945 0.3048)
			(stroke
				(width 0.1)
				(type default)
			)
			(layer "B.Fab")
		)
		(fp_line
			(start 0.12065 -0.2794)
			(end -0.12065 -0.2794)
			(stroke
				(width 0.1)
				(type default)
			)
			(layer "B.Fab")
		)
		(fp_line
			(start -0.12065 -0.2794)
			(end -0.12065 -0.3048)
			(stroke
				(width 0.1)
				(type default)
			)
			(layer "B.Fab")
		)
		(fp_line
			(start 0.12065 0.2794)
			(end 0.12065 0.3048)
			(stroke
				(width 0.1)
				(type default)
			)
			(layer "B.Fab")
		)
		(fp_line
			(start -0.120396 0.2794)
			(end 0.12065 0.2794)
			(stroke
				(width 0.1)
				(type default)
			)
			(layer "B.Fab")
		)
		(fp_line
			(start 0.67945 0.3048)
			(end 0.67945 -0.305054)
			(stroke
				(width 0.1)
				(type default)
			)
			(layer "B.Fab")
		)
		(fp_line
			(start 0.12065 0.3048)
			(end 0.67945 0.3048)
			(stroke
				(width 0.1)
				(type default)
			)
			(layer "B.Fab")
		)
		(fp_line
			(start -0.120396 0.3048)
			(end -0.120396 0.2794)
			(stroke
				(width 0.1)
				(type default)
			)
			(layer "B.Fab")
		)
		(fp_line
			(start -0.67945 0.3048)
			(end -0.120396 0.3048)
			(stroke
				(width 0.1)
				(type default)
			)
			(layer "B.Fab")
		)
		(pad "1" smd circle
			(at 0.40005 0 270)
			(size 0 0)
			(layers "B.Cu" "B.Mask" "B.Paste")
			(net "FM_PCH_P1V8_AUX_EN")
		)
		(pad "2" smd circle
			(at -0.40005 0 270)
			(size 0 0)
			(layers "B.Cu" "B.Mask" "B.Paste")
			(net "FM_PCH_P1V8_AUX_EN_R")
		)
	)
)
